(kicad_pcb
	(version 20260206)
	(generator "pcbnew")
	(generator_version "10.0")
	(general
		(thickness 1.6)
		(legacy_teardrops no)
	)
	(paper "A4")
	(title_block
		(title "peb — Lightning_PEB_BRD.brd")
		(comment 1 "Lightning (Wiwynn / Facebook NVMe JBOF) / footprints 1271-1277 of 2563")
	)
	(layers
		(0 "F.Cu" signal "TOP")
		(4 "In1.Cu" signal "L2GND")
		(6 "In2.Cu" signal "L3")
		(8 "In3.Cu" signal "L4VCC")
		(10 "In4.Cu" signal "L5VCC")
		(12 "In5.Cu" signal "L6")
		(14 "In6.Cu" signal "L7GND")
		(2 "B.Cu" signal "BOTTOM")
		(9 "F.Adhes" user "F.Adhesive")
		(11 "B.Adhes" user "B.Adhesive")
		(13 "F.Paste" user "Package Geometry/Pastemask Top")
		(15 "B.Paste" user "Package Geometry/Pastemask Bottom")
		(5 "F.SilkS" user "Ref Des/Silkscreen Top")
		(7 "B.SilkS" user "Ref Des/Silkscreen Bottom")
		(1 "F.Mask" user "Board Geometry/Soldermask Top")
		(3 "B.Mask" user "Board Geometry/Soldermask Bottom")
		(17 "Dwgs.User" user "User.Drawings")
		(19 "Cmts.User" user "User.Comments")
		(21 "Eco1.User" user "User.Eco1")
		(23 "Eco2.User" user "User.Eco2")
		(25 "Edge.Cuts" user "Board Geometry/Outline")
		(27 "Margin" user)
		(31 "F.CrtYd" user "Package Geometry/Place Bound Top")
		(29 "B.CrtYd" user "Package Geometry/Place Bound Bottom")
		(35 "F.Fab" user "Ref Des/Assembly Top")
		(33 "B.Fab" user "Ref Des/Assembly Bottom")
	)
	(footprint ""
		(layer "F.Cu")
		(at 318.77 -69.215 180)
		(property "Reference" "PTC6"
			(at 0 0 180)
			(layer "F.SilkS")
			(hide yes)
			(effects
				(font
					(size 1.27 1.27)
				)
			)
		)
		(property "Value" "SE470UF2VDM-GP"
			(at 0 -9.6012 180)
			(unlocked yes)
			(layer "F.Fab")
			(hide yes)
			(effects
				(font
					(size 1.016 1.016)
					(thickness 0.1524)
				)
			)
		)
		(property "Device Type" "CT7343H83"
			(at 0 -11.1252 180)
			(unlocked yes)
			(layer "F.Fab")
			(hide yes)
			(effects
				(font
					(size 1.016 1.016)
					(thickness 0.1524)
				)
			)
		)
		(duplicate_pad_numbers_are_jumpers no)
		(fp_line
			(start 2.286 4.8768)
			(end -2.286 4.8768)
			(stroke
				(width 0.1524)
				(type default)
			)
			(layer "F.SilkS")
		)
		(fp_line
			(start 2.286 2.032)
			(end 2.286 4.8768)
			(stroke
				(width 0.1524)
				(type default)
			)
			(layer "F.SilkS")
		)
		(fp_line
			(start 2.286 -2.032)
			(end 2.286 -4.8768)
			(stroke
				(width 0.1524)
				(type default)
			)
			(layer "F.SilkS")
		)
		(fp_line
			(start 2.286 -4.8768)
			(end -2.286 -4.8768)
			(stroke
				(width 0.1524)
				(type default)
			)
			(layer "F.SilkS")
		)
		(fp_line
			(start 2.1082 -4.699)
			(end -2.1082 -4.699)
			(stroke
				(width 0.508)
				(type default)
			)
			(layer "F.SilkS")
		)
		(fp_line
			(start -2.286 4.8768)
			(end -2.286 2.032)
			(stroke
				(width 0.1524)
				(type default)
			)
			(layer "F.SilkS")
		)
		(fp_line
			(start -2.286 -4.8768)
			(end -2.286 -2.032)
			(stroke
				(width 0.1524)
				(type default)
			)
			(layer "F.SilkS")
		)
		(fp_rect
			(start -2.1463 3.6449)
			(end 2.1463 -3.6449)
			(stroke
				(width 0)
				(type default)
			)
			(fill no)
			(layer "F.CrtYd")
		)
		(fp_poly
			(pts
				(xy -2.54 4.953) (xy -2.54 4.2926) (xy -3.81 4.2926) (xy -3.81 -4.2926) (xy -2.54 -4.2926) (xy -2.54 -4.953)
				(xy 2.54 -4.953) (xy 2.54 -4.2926) (xy 3.81 -4.2926) (xy 3.81 -1.6256) (xy 2.1463 -1.6256) (xy 2.1463 -3.6449)
				(xy -2.1463 -3.6449) (xy -2.1463 3.6449) (xy 2.1463 3.6449) (xy 2.1463 -1.6129) (xy 3.81 -1.6129)
				(xy 3.81 4.2926) (xy 2.54 4.2926) (xy 2.54 4.953)
			)
			(stroke
				(width 0)
				(type default)
			)
			(fill no)
			(layer "F.CrtYd")
		)
		(fp_rect
			(start 2.54 4.2926)
			(end 3.81 -4.2926)
			(stroke
				(width 0)
				(type default)
			)
			(fill no)
			(layer "F.Fab")
		)
		(fp_rect
			(start -2.54 4.953)
			(end 2.54 -4.953)
			(stroke
				(width 0)
				(type default)
			)
			(fill no)
			(layer "F.Fab")
		)
		(fp_rect
			(start -3.81 4.2926)
			(end -2.54 -4.2926)
			(stroke
				(width 0)
				(type default)
			)
			(fill no)
			(layer "F.Fab")
		)
		(pad "1" smd rect
			(at 0 -3.1496 180)
			(size 2.413 2.286)
			(layers "F.Cu" "F.Mask" "F.Paste")
			(net "P0V9_E")
		)
		(pad "2" smd rect
			(at 0 3.1496 180)
			(size 2.413 2.286)
			(layers "F.Cu" "F.Mask" "F.Paste")
			(net "GND")
		)
		(zone
			(layer "F.Cu")
			(hatch none 0.5)
			(connect_pads
				(clearance 0)
			)
			(min_thickness 0.25)
			(keepout
				(tracks allowed)
				(vias not_allowed)
				(pads allowed)
				(copperpour not_allowed)
				(footprints allowed)
			)
			(placement
				(enabled no)
				(sheetname "")
			)
			(fill
				(thermal_gap 0.5)
				(thermal_bridge_width 0.5)
				(island_removal_mode 0)
			)
			(polygon
				(pts
					(xy 317.2587 -67.5259) (xy 317.2587 -64.6176) (xy 320.2813 -64.6176) (xy 320.2813 -67.5132) (xy 320.2813 -67.8434)
					(xy 317.2587 -67.8434)
				)
			)
		)
		(zone
			(layer "F.Cu")
			(hatch none 0.5)
			(connect_pads
				(clearance 0)
			)
			(min_thickness 0.25)
			(keepout
				(tracks allowed)
				(vias not_allowed)
				(pads allowed)
				(copperpour not_allowed)
				(footprints allowed)
			)
			(placement
				(enabled no)
				(sheetname "")
			)
			(fill
				(thermal_gap 0.5)
				(thermal_bridge_width 0.5)
				(island_removal_mode 0)
			)
			(polygon
				(pts
					(xy 320.2813 -73.8124) (xy 317.2587 -73.8124) (xy 317.2587 -70.9168) (xy 317.2587 -70.5866) (xy 320.2813 -70.5866)
					(xy 320.2813 -70.9168)
				)
			)
		)
	)
	(footprint ""
		(layer "F.Cu")
		(at 138.392154 -212.420454 180)
		(property "Reference" "C344"
			(at 0 0 180)
			(layer "F.SilkS")
			(hide yes)
			(effects
				(font
					(size 1.27 1.27)
				)
			)
		)
		(property "Value" "SCD22U10V2KX-1GP"
			(at 1.1811 -2.7051 180)
			(unlocked yes)
			(layer "F.Fab")
			(hide yes)
			(effects
				(font
					(size 1.016 1.016)
					(thickness 0.1524)
				)
			)
		)
		(property "Device Type" "C402H22"
			(at 1.1811 -4.2291 180)
			(unlocked yes)
			(layer "F.Fab")
			(hide yes)
			(effects
				(font
					(size 1.016 1.016)
					(thickness 0.1524)
				)
			)
		)
		(duplicate_pad_numbers_are_jumpers no)
		(fp_rect
			(start -0.4318 0.9525)
			(end 0.4318 -0.9525)
			(stroke
				(width 0)
				(type default)
			)
			(fill no)
			(layer "F.CrtYd")
		)
		(fp_rect
			(start -0.4318 0.9525)
			(end 0.4318 -0.9525)
			(stroke
				(width 0)
				(type default)
			)
			(fill no)
			(layer "F.Fab")
		)
		(pad "1" smd custom
			(at 0 -0.4445 180)
			(size 0.1524 0.1524)
			(layers "F.Cu" "F.Mask" "F.Paste")
			(net "PCIE_TX_CAP_P59")
			(options
				(clearance outline)
				(anchor circle)
			)
			(primitives
				(gr_poly
					(pts
						(arc
							(start 0.3048 -0.2032)
							(mid 0.275042 -0.275042)
							(end 0.2032 -0.3048)
						)
						(arc
							(start -0.2032 -0.3048)
							(mid -0.275042 -0.275042)
							(end -0.3048 -0.2032)
						)
						(arc
							(start -0.3048 0.2032)
							(mid -0.275042 0.275042)
							(end -0.2032 0.3048)
						)
						(arc
							(start 0.2032 0.3048)
							(mid 0.275042 0.275042)
							(end 0.3048 0.2032)
						)
					)
					(width 0)
					(fill yes)
				)
			)
		)
		(pad "2" smd custom
			(at 0 0.4445 180)
			(size 0.1524 0.1524)
			(layers "F.Cu" "F.Mask" "F.Paste")
			(net "PCIE_TX_P59")
			(options
				(clearance outline)
				(anchor circle)
			)
			(primitives
				(gr_poly
					(pts
						(arc
							(start 0.3048 -0.2032)
							(mid 0.275042 -0.275042)
							(end 0.2032 -0.3048)
						)
						(arc
							(start -0.2032 -0.3048)
							(mid -0.275042 -0.275042)
							(end -0.3048 -0.2032)
						)
						(arc
							(start -0.3048 0.2032)
							(mid -0.275042 0.275042)
							(end -0.2032 0.3048)
						)
						(arc
							(start 0.2032 0.3048)
							(mid 0.275042 0.275042)
							(end 0.3048 0.2032)
						)
					)
					(width 0)
					(fill yes)
				)
			)
		)
	)
	(footprint ""
		(layer "F.Cu")
		(at 296.672 -57.0992)
		(property "Reference" "C424"
			(at 0 0 0)
			(layer "F.SilkS")
			(hide yes)
			(effects
				(font
					(size 1.27 1.27)
				)
			)
		)
		(property "Value" "SC10U16V5KX-1-GP"
			(at -0.0762 -6.1214 0)
			(unlocked yes)
			(layer "F.Fab")
			(hide yes)
			(effects
				(font
					(size 1.016 1.016)
					(thickness 0.1524)
				)
			)
		)
		(property "Device Type" "C805H54"
			(at -0.0762 -8.1534 0)
			(unlocked yes)
			(layer "F.Fab")
			(hide yes)
			(effects
				(font
					(size 1.016 1.016)
					(thickness 0.1524)
				)
			)
		)
		(duplicate_pad_numbers_are_jumpers no)
		(fp_line
			(start 0.635 0)
			(end -0.635 0)
			(stroke
				(width 0.508)
				(type default)
			)
			(layer "F.SilkS")
		)
		(fp_rect
			(start -0.9652 1.778)
			(end 0.9652 -1.778)
			(stroke
				(width 0)
				(type default)
			)
			(fill no)
			(layer "F.CrtYd")
		)
		(fp_poly
			(pts
				(xy -0.9652 -1.778) (xy 0.9652 -1.778) (xy 0.9652 1.778) (xy -0.9652 1.778)
			)
			(stroke
				(width 0)
				(type default)
			)
			(fill no)
			(layer "F.Fab")
		)
		(pad "1" smd rect
			(at 0 -0.9652)
			(size 1.397 1.143)
			(layers "F.Cu" "F.Mask" "F.Paste")
			(net "DUT_VDD")
		)
		(pad "2" smd rect
			(at 0 0.9652)
			(size 1.397 1.143)
			(layers "F.Cu" "F.Mask" "F.Paste")
			(net "GND")
		)
	)
	(footprint ""
		(layer "F.Cu")
		(at 181.19725 -6.655308)
		(property "Reference" "R717"
			(at 0 0 0)
			(layer "F.SilkS")
			(hide yes)
			(effects
				(font
					(size 1.27 1.27)
				)
			)
		)
		(property "Value" "0R2J-2-GP"
			(at 0.064008 -3.993896 0)
			(unlocked yes)
			(layer "F.Fab")
			(hide yes)
			(effects
				(font
					(size 1.016 1.016)
					(thickness 0.1524)
				)
			)
		)
		(property "Device Type" "R402H16"
			(at 0.064008 -5.517896 0)
			(unlocked yes)
			(layer "F.Fab")
			(hide yes)
			(effects
				(font
					(size 1.016 1.016)
					(thickness 0.1524)
				)
			)
		)
		(duplicate_pad_numbers_are_jumpers no)
		(fp_line
			(start -0.508 -0.9398)
			(end -0.508 0.9398)
			(stroke
				(width 0.1524)
				(type default)
			)
			(layer "F.SilkS")
		)
		(fp_line
			(start 0.508 -0.9398)
			(end -0.508 -0.9398)
			(stroke
				(width 0.1524)
				(type default)
			)
			(layer "F.SilkS")
		)
		(fp_rect
			(start -0.508 0.9398)
			(end 0.508 -0.9398)
			(stroke
				(width 0)
				(type default)
			)
			(fill no)
			(layer "F.CrtYd")
		)
		(fp_rect
			(start -0.508 0.9398)
			(end 0.508 -0.9398)
			(stroke
				(width 0)
				(type default)
			)
			(fill no)
			(layer "F.Fab")
		)
		(pad "1" smd custom
			(at 0 -0.4445)
			(size 0.1397 0.1397)
			(layers "F.Cu" "F.Mask" "F.Paste")
			(net "HOST4_RST_N_C")
			(options
				(clearance outline)
				(anchor circle)
			)
			(primitives
				(gr_poly
					(pts
						(arc
							(start -0.1778 -0.2794)
							(mid -0.249642 -0.249642)
							(end -0.2794 -0.1778)
						)
						(arc
							(start -0.2794 0.1778)
							(mid -0.249642 0.249642)
							(end -0.1778 0.2794)
						)
						(arc
							(start 0.1778 0.2794)
							(mid 0.249642 0.249642)
							(end 0.2794 0.1778)
						)
						(arc
							(start 0.2794 -0.1778)
							(mid 0.249642 -0.249642)
							(end 0.1778 -0.2794)
						)
					)
					(width 0)
					(fill yes)
				)
			)
		)
		(pad "2" smd custom
			(at 0 0.4445)
			(size 0.1397 0.1397)
			(layers "F.Cu" "F.Mask" "F.Paste")
			(net "P3V3_STBY")
			(options
				(clearance outline)
				(anchor circle)
			)
			(primitives
				(gr_poly
					(pts
						(arc
							(start -0.1778 -0.2794)
							(mid -0.249642 -0.249642)
							(end -0.2794 -0.1778)
						)
						(arc
							(start -0.2794 0.1778)
							(mid -0.249642 0.249642)
							(end -0.1778 0.2794)
						)
						(arc
							(start 0.1778 0.2794)
							(mid 0.249642 0.249642)
							(end 0.2794 0.1778)
						)
						(arc
							(start 0.2794 -0.1778)
							(mid 0.249642 -0.249642)
							(end 0.1778 -0.2794)
						)
					)
					(width 0)
					(fill yes)
				)
			)
		)
	)
	(footprint ""
		(layer "F.Cu")
		(at 7.493 -133.873748 -90)
		(property "Reference" "D1403"
			(at 0 0 270)
			(layer "F.SilkS")
			(hide yes)
			(effects
				(font
					(size 1.27 1.27)
				)
			)
		)
		(property "Value" "RB551V30-GP"
			(at 0 -6.7818 270)
			(unlocked yes)
			(layer "F.Fab")
			(hide yes)
			(effects
				(font
					(size 1.016 1.016)
					(thickness 0.1524)
				)
			)
		)
		(property "Device Type" "SOD323AKH38"
			(at 0 -8.6868 270)
			(unlocked yes)
			(layer "F.Fab")
			(hide yes)
			(effects
				(font
					(size 1.016 1.016)
					(thickness 0.1524)
				)
			)
		)
		(duplicate_pad_numbers_are_jumpers no)
		(fp_line
			(start -0.889 2.159)
			(end -0.889 -1.9304)
			(stroke
				(width 0.1524)
				(type default)
			)
			(layer "F.SilkS")
		)
		(fp_line
			(start 0.889 2.159)
			(end -0.889 2.159)
			(stroke
				(width 0.1524)
				(type default)
			)
			(layer "F.SilkS")
		)
		(fp_line
			(start 0.762 2.0574)
			(end -0.762 2.0574)
			(stroke
				(width 0.508)
				(type default)
			)
			(layer "F.SilkS")
		)
		(fp_line
			(start -0.889 -1.9304)
			(end 0.889 -1.9304)
			(stroke
				(width 0.1524)
				(type default)
			)
			(layer "F.SilkS")
		)
		(fp_line
			(start 0.889 -1.9304)
			(end 0.889 2.159)
			(stroke
				(width 0.1524)
				(type default)
			)
			(layer "F.SilkS")
		)
		(fp_rect
			(start -1.016 2.3114)
			(end 1.016 -2.0066)
			(stroke
				(width 0)
				(type default)
			)
			(fill no)
			(layer "F.CrtYd")
		)
		(fp_poly
			(pts
				(xy -1.016 -2.0066) (xy 1.016 -2.0066) (xy 1.016 2.3114) (xy -1.016 2.3114)
			)
			(stroke
				(width 0)
				(type default)
			)
			(fill no)
			(layer "F.Fab")
		)
		(pad "A" smd rect
			(at 0 -1.143 270)
			(size 0.5588 1.016)
			(layers "F.Cu" "F.Mask" "F.Paste")
			(net "TRAY_RESET_N_R")
		)
		(pad "K" smd rect
			(at 0 1.143 270)
			(size 0.5588 1.016)
			(layers "F.Cu" "F.Mask" "F.Paste")
			(net "TRAY_RESET_N")
		)
	)
	(footprint ""
		(layer "F.Cu")
		(at 19.7612 -53.6194 180)
		(property "Reference" "R515"
			(at 0 0 180)
			(layer "F.SilkS")
			(hide yes)
			(effects
				(font
					(size 1.27 1.27)
				)
			)
		)
		(property "Value" "0R2J-2-GP"
			(at 0.064008 -3.993896 180)
			(unlocked yes)
			(layer "F.Fab")
			(hide yes)
			(effects
				(font
					(size 1.016 1.016)
					(thickness 0.1524)
				)
			)
		)
		(property "Device Type" "R402H16"
			(at 0.064008 -5.517896 180)
			(unlocked yes)
			(layer "F.Fab")
			(hide yes)
			(effects
				(font
					(size 1.016 1.016)
					(thickness 0.1524)
				)
			)
		)
		(duplicate_pad_numbers_are_jumpers no)
		(fp_line
			(start 0.508 -0.9398)
			(end -0.508 -0.9398)
			(stroke
				(width 0.1524)
				(type default)
			)
			(layer "F.SilkS")
		)
		(fp_line
			(start -0.508 -0.9398)
			(end -0.508 0.9398)
			(stroke
				(width 0.1524)
				(type default)
			)
			(layer "F.SilkS")
		)
		(fp_rect
			(start -0.508 0.9398)
			(end 0.508 -0.9398)
			(stroke
				(width 0)
				(type default)
			)
			(fill no)
			(layer "F.CrtYd")
		)
		(fp_rect
			(start -0.508 0.9398)
			(end 0.508 -0.9398)
			(stroke
				(width 0)
				(type default)
			)
			(fill no)
			(layer "F.Fab")
		)
		(pad "1" smd custom
			(at 0 -0.4445 180)
			(size 0.1397 0.1397)
			(layers "F.Cu" "F.Mask" "F.Paste")
			(net "NIC0_MDI0_N2_R")
			(options
				(clearance outline)
				(anchor circle)
			)
			(primitives
				(gr_poly
					(pts
						(arc
							(start -0.1778 -0.2794)
							(mid -0.249642 -0.249642)
							(end -0.2794 -0.1778)
						)
						(arc
							(start -0.2794 0.1778)
							(mid -0.249642 0.249642)
							(end -0.1778 0.2794)
						)
						(arc
							(start 0.1778 0.2794)
							(mid 0.249642 0.249642)
							(end 0.2794 0.1778)
						)
						(arc
							(start 0.2794 -0.1778)
							(mid 0.249642 -0.249642)
							(end 0.1778 -0.2794)
						)
					)
					(width 0)
					(fill yes)
				)
			)
		)
		(pad "2" smd custom
			(at 0 0.4445 180)
			(size 0.1397 0.1397)
			(layers "F.Cu" "F.Mask" "F.Paste")
			(net "NIC0_MDI0_N2")
			(options
				(clearance outline)
				(anchor circle)
			)
			(primitives
				(gr_poly
					(pts
						(arc
							(start -0.1778 -0.2794)
							(mid -0.249642 -0.249642)
							(end -0.2794 -0.1778)
						)
						(arc
							(start -0.2794 0.1778)
							(mid -0.249642 0.249642)
							(end -0.1778 0.2794)
						)
						(arc
							(start 0.1778 0.2794)
							(mid 0.249642 0.249642)
							(end 0.2794 0.1778)
						)
						(arc
							(start 0.2794 -0.1778)
							(mid 0.249642 -0.249642)
							(end 0.1778 -0.2794)
						)
					)
					(width 0)
					(fill yes)
				)
			)
		)
	)
	(footprint ""
		(layer "F.Cu")
		(at 52.578 -198.247 90)
		(property "Reference" "C705"
			(at 0 0 90)
			(layer "F.SilkS")
			(hide yes)
			(effects
				(font
					(size 1.27 1.27)
				)
			)
		)
		(property "Value" "SC220P50V3JN-GP"
			(at 0 -2.8194 90)
			(unlocked yes)
			(layer "F.Fab")
			(hide yes)
			(effects
				(font
					(size 1.016 1.016)
					(thickness 0.1524)
				)
			)
		)
		(property "Device Type" "C603H36"
			(at 0 -4.3434 90)
			(unlocked yes)
			(layer "F.Fab")
			(hide yes)
			(effects
				(font
					(size 1.016 1.016)
					(thickness 0.1524)
				)
			)
		)
		(duplicate_pad_numbers_are_jumpers no)
		(fp_line
			(start 0.508 0)
			(end -0.508 0)
			(stroke
				(width 0.2032)
				(type default)
			)
			(layer "F.SilkS")
		)
		(fp_rect
			(start -0.5842 1.3335)
			(end 0.5842 -1.3335)
			(stroke
				(width 0)
				(type default)
			)
			(fill no)
			(layer "F.CrtYd")
		)
		(fp_rect
			(start -0.5842 1.3335)
			(end 0.5842 -1.3335)
			(stroke
				(width 0)
				(type default)
			)
			(fill no)
			(layer "F.Fab")
		)
		(pad "1" smd custom
			(at 0 -0.762 90)
			(size 0.2159 0.2159)
			(layers "F.Cu" "F.Mask" "F.Paste")
			(net "BUF_I2C7_B_DBP_SCL_R")
			(options
				(clearance outline)
				(anchor circle)
			)
			(primitives
				(gr_poly
					(pts
						(arc
							(start -0.3302 -0.4318)
							(mid -0.402042 -0.402042)
							(end -0.4318 -0.3302)
						)
						(arc
							(start -0.4318 0.3302)
							(mid -0.402042 0.402042)
							(end -0.3302 0.4318)
						)
						(arc
							(start 0.3302 0.4318)
							(mid 0.402042 0.402042)
							(end 0.4318 0.3302)
						)
						(arc
							(start 0.4318 -0.3302)
							(mid 0.402042 -0.402042)
							(end 0.3302 -0.4318)
						)
					)
					(width 0)
					(fill yes)
				)
			)
		)
		(pad "2" smd custom
			(at 0 0.762 90)
			(size 0.2159 0.2159)
			(layers "F.Cu" "F.Mask" "F.Paste")
			(net "GND")
			(options
				(clearance outline)
				(anchor circle)
			)
			(primitives
				(gr_poly
					(pts
						(arc
							(start -0.3302 -0.4318)
							(mid -0.402042 -0.402042)
							(end -0.4318 -0.3302)
						)
						(arc
							(start -0.4318 0.3302)
							(mid -0.402042 0.402042)
							(end -0.3302 0.4318)
						)
						(arc
							(start 0.3302 0.4318)
							(mid 0.402042 0.402042)
							(end 0.4318 0.3302)
						)
						(arc
							(start 0.4318 -0.3302)
							(mid 0.402042 -0.402042)
							(end 0.3302 -0.4318)
						)
					)
					(width 0)
					(fill yes)
				)
			)
		)
	)
)
